# S9S_MB_2U (Grand Teton) — schematic netlist excerpt (pin names and nets, part order shuffled) for the footprints in the layout excerpt that follows; sources: Cadence DE-HDL packaged netlist, KiCad conversion of 03242023_DA0F0TMBIJ0_F0T_Motherboard_J_brd_V01_OCP.brd

J1  SCONN288_ADR50017P130CC  SCONN288_ADR50017-P130CC IO  pkg DDR288S_1-1VXB  page 82
  VIN_BULK0  = P12V_S3_AUX_CPU0_NVDIMM
  RFU0  = TP_CHA_CPU0_DIMM1_FRU_0
  VIN_MGMT  = P3V3_AUX
  HSCL  = I3C_SPD_DDRABCD_CPU0_LVC1_SCL_R
  HSDA  = I3C_SPD_DDRABCD_CPU0_LVC1_SDA
  VSS0  = GND
  DQ0_A  = M_A_CPU0_SA_DQ<0>
  VSS1  = GND
  DQ1_A  = M_A_CPU0_SA_DQ<1>
  VSS2  = GND
  DQS0_A_T  = M_A_CPU0_SA_DQS_DP<0>
  DQS0_A_C  = M_A_CPU0_SA_DQS_DN<0>
  VSS3  = GND
  DQ4_A  = M_A_CPU0_SA_DQ<4>
  VSS4  = GND
  DQ5_A  = M_A_CPU0_SA_DQ<5>
  VSS5  = GND
  DQ8_A  = M_A_CPU0_SA_DQ<8>
  VSS6  = GND
  DQ9_A  = M_A_CPU0_SA_DQ<9>
  VSS7  = GND
  DQS1_A_T  = M_A_CPU0_SA_DQS_DP<1>
  DQS1_A_C  = M_A_CPU0_SA_DQS_DN<1>
  VSS8  = GND
  DQ12_A  = M_A_CPU0_SA_DQ<12>
  VSS9  = GND
  DQ13_A  = M_A_CPU0_SA_DQ<13>
  VSS10  = GND
  DQ16_A  = M_A_CPU0_SA_DQ<16>
  VSS11  = GND
  DQ17_A  = M_A_CPU0_SA_DQ<17>
  VSS12  = GND
  DQS2_A_T  = M_A_CPU0_SA_DQS_DP<2>
  DQS2_A_C  = M_A_CPU0_SA_DQS_DN<2>
  VSS13  = GND
  DQ20_A  = M_A_CPU0_SA_DQ<20>
  VSS14  = GND
  DQ21_A  = M_A_CPU0_SA_DQ<21>
  VSS15  = GND
  DQ24_A  = M_A_CPU0_SA_DQ<24>
  VSS16  = GND
  DQ25_A  = M_A_CPU0_SA_DQ<25>
  VSS17  = GND
  DQS3_A_T  = M_A_CPU0_SA_DQS_DP<3>
  DQS3_A_C  = M_A_CPU0_SA_DQS_DN<3>
  VSS18  = GND
  DQ28_A  = M_A_CPU0_SA_DQ<28>
  VSS19  = GND
  DQ29_A  = M_A_CPU0_SA_DQ<29>
  VSS20  = GND
  CB0_A  = M_A_CPU0_SA_CB<0>
  VSS21  = GND
  CB1_A  = M_A_CPU0_SA_CB<1>
  VSS22  = GND
  DQS4_A_T  = M_A_CPU0_SA_DQS_DP<4>
  DQS4_A_C  = M_A_CPU0_SA_DQS_DN<4>
  VSS23  = GND
  CB4_A  = M_A_CPU0_SA_CB<4>
  VSS24  = GND
  CB5_A  = M_A_CPU0_SA_CB<5>
  VSS25  = GND
  ALERT_N  = M_A_CPU0_ALERT_N
  VSS26  = GND
  CS0_A_N  = M_A_CPU0_SA_CS_N<0>
  VSS27  = GND
  CA0_A  = M_A_CPU0_SA_CA<0>
  VSS28  = GND
  CA2_A  = M_A_CPU0_SA_CA<2>
  VSS29  = GND
  CA4_A  = M_A_CPU0_SA_CA<4>
  VSS30  = GND
  CA6_A  = M_A_CPU0_SA_CA<6>
  VSS31  = GND
  PAR_A  = M_A_CPU0_SA_PAR
  VSS32  = GND
  CA0_B  = M_A_CPU0_SB_CA<0>
  VSS33  = GND
  CA2_B  = M_A_CPU0_SB_CA<2>
  VSS34  = GND
  CA4_B  = M_A_CPU0_SB_CA<4>
  VSS35  = GND
  CA6_B  = M_A_CPU0_SB_CA<6>
  VSS36  = GND
  CS0_B_N  = M_A_CPU0_SB_CS_N<0>
  VSS37  = GND
  \lbd||rsp_a_n\  = M_A_CPU0_SA_RSP<0>
  \lbs||rsp_b_n\  = M_A_CPU0_SB_RSP<0>
  VSS38  = GND
  CB4_B  = M_A_CPU0_SB_CB<4>
  VSS39  = GND
  CB5_B  = M_A_CPU0_SB_CB<5>
  VSS40  = GND
  \dqs9_b_t||tdqs9_b_t||dbi4_b_n\  = M_A_CPU0_SB_DQS_DP<9>
  \dqs9_b_c||tdqs9_b_c\  = M_A_CPU0_SB_DQS_DN<9>
  VSS41  = GND
  CB0_B  = M_A_CPU0_SB_CB<0>
  VSS42  = GND
  CB1_B  = M_A_CPU0_SB_CB<1>
  VSS43  = GND
  DQ0_B  = M_A_CPU0_SB_DQ<0>
  VSS44  = GND
  DQ1_B  = M_A_CPU0_SB_DQ<1>
  VSS45  = GND
  DQS0_B_T  = M_A_CPU0_SB_DQS_DP<0>
  DQS0_B_C  = M_A_CPU0_SB_DQS_DN<0>
  VSS46  = GND
  DQ4_B  = M_A_CPU0_SB_DQ<4>
  VSS47  = GND
  DQ5_B  = M_A_CPU0_SB_DQ<5>
  VSS48  = GND
  DQ8_B  = M_A_CPU0_SB_DQ<8>
  VSS49  = GND
  DQ9_B  = M_A_CPU0_SB_DQ<9>
  VSS50  = GND
  DQS1_B_T  = M_A_CPU0_SB_DQS_DP<1>
  DQS1_B_C  = M_A_CPU0_SB_DQS_DN<1>
  VSS51  = GND
  DQ12_B  = M_A_CPU0_SB_DQ<12>
  VSS52  = GND
  DQ13_B  = M_A_CPU0_SB_DQ<13>
  VSS53  = GND
  DQ16_B  = M_A_CPU0_SB_DQ<16>
  VSS54  = GND
  DQ17_B  = M_A_CPU0_SB_DQ<17>
  VSS55  = GND
  DQS2_B_T  = M_A_CPU0_SB_DQS_DP<2>
  DQS2_B_C  = M_A_CPU0_SB_DQS_DN<2>
  VSS56  = GND
  DQ20_B  = M_A_CPU0_SB_DQ<20>
  VSS57  = GND
  DQ21_B  = M_A_CPU0_SB_DQ<21>
  VSS58  = GND
  DQ24_B  = M_A_CPU0_SB_DQ<24>
  VSS59  = GND
  DQ25_B  = M_A_CPU0_SB_DQ<25>
  VSS60  = GND
  DQS3_B_T  = M_A_CPU0_SB_DQS_DP<3>
  DQS3_B_C  = M_A_CPU0_SB_DQS_DN<3>
  VSS61  = GND
  DQ28_B  = M_A_CPU0_SB_DQ<28>
  VSS62  = GND
  DQ29_B  = M_A_CPU0_SB_DQ<29>
  VSS63  = GND
  RFU1  = TP_CHA_CPU0_DIMM1_FRU_1
  VIN_BULK1  = P12V_S3_AUX_CPU0_NVDIMM
  VIN_BULK2  = P12V_S3_AUX_CPU0_NVDIMM
  \pwr_good||fail_n\  = PWRGD_CHA_CPU0_DIMM1
  HSA  = PD_CHA_CPU0_DIMM1_SAA
  RFU2  = TP_CHA_CPU0_DIMM1_FRU_2
  RFU3  = TP_CHA_CPU0_DIMM1_FRU_3
  VSS64  = GND
  DQ2_A  = M_A_CPU0_SA_DQ<2>
  VSS65  = GND
  DQ3_A  = M_A_CPU0_SA_DQ<3>
  VSS66  = GND
  \dqs5_a_c||tdqs5_a_c||dqs5_a_t||tdqs5_a_t\  = M_A_CPU0_SA_DQS_DN<5>
  \dqs5_a_t||tdqs5_a_t\  = M_A_CPU0_SA_DQS_DP<5>
  VSS67  = GND
  DQ6_A  = M_A_CPU0_SA_DQ<6>
  VSS68  = GND
  DQ7_A  = M_A_CPU0_SA_DQ<7>
  VSS69  = GND
  DQ10_A  = M_A_CPU0_SA_DQ<10>
  VSS70  = GND
  DQ11_A  = M_A_CPU0_SA_DQ<11>
  VSS71  = GND
  \dqs6_a_c||tdqs6_a_c||dqs6_a_t||tdqs6_a_t\  = M_A_CPU0_SA_DQS_DN<6>
  \dqs6_a_t||tdqs6_a_t\  = M_A_CPU0_SA_DQS_DP<6>
  VSS72  = GND
  DQ14_A  = M_A_CPU0_SA_DQ<14>
  VSS73  = GND
  DQ15_A  = M_A_CPU0_SA_DQ<15>
  VSS74  = GND
  DQ18_A  = M_A_CPU0_SA_DQ<18>
  VSS75  = GND
  DQ19_A  = M_A_CPU0_SA_DQ<19>
  VSS76  = GND
  \dqs7_a_c||tdqs7_a_c\  = M_A_CPU0_SA_DQS_DN<7>
  \dqs7_a_t||tdqs7_a_t\  = M_A_CPU0_SA_DQS_DP<7>
  VSS77  = GND
  DQ22_A  = M_A_CPU0_SA_DQ<22>
  VSS78  = GND
  DQ23_A  = M_A_CPU0_SA_DQ<23>
  VSS79  = GND
  DQ26_A  = M_A_CPU0_SA_DQ<26>
  VSS80  = GND
  DQ27_A  = M_A_CPU0_SA_DQ<27>
  VSS81  = GND
  \dqs8_a_c||tdqs8_a_c\  = M_A_CPU0_SA_DQS_DN<8>
  \dqs8_a_t||tdqs8_a_t\  = M_A_CPU0_SA_DQS_DP<8>
  VSS82  = GND
  DQ30_A  = M_A_CPU0_SA_DQ<30>
  VSS83  = GND
  DQ31_A  = M_A_CPU0_SA_DQ<31>
  VSS84  = GND
  CB2_A  = M_A_CPU0_SA_CB<2>
  VSS85  = GND
  CB3_A  = M_A_CPU0_SA_CB<3>
  VSS86  = GND
  \dqs9_a_c||tdqs9_a_c\  = M_A_CPU0_SA_DQS_DN<9>
  \dqs9_a_t||tdqs9_a_t\  = M_A_CPU0_SA_DQS_DP<9>
  VSS87  = GND
  CB6_A  = M_A_CPU0_SA_CB<6>
  VSS88  = GND
  CB7_A  = M_A_CPU0_SA_CB<7>
  VSS89  = GND
  RESET_N  = RST_M_AB_CPU0_FPGA_N
  VSS90  = GND
  CS1_A_N  = M_A_CPU0_SA_CS_N<1>
  VSS91  = GND
  CA1_A  = M_A_CPU0_SA_CA<1>
  VSS92  = GND
  CA3_A  = M_A_CPU0_SA_CA<3>
  VSS93  = GND
  CA5_A  = M_A_CPU0_SA_CA<5>
  VSS94  = GND
  CK_T  = M_A_CPU0_CLK_DP<0>
  CK_C  = M_A_CPU0_CLK_DN<0>
  VSS95  = GND
  RFU4  = TP_CHA_CPU0_DIMM1_FRU_4
  CA1_B  = M_A_CPU0_SB_CA<1>
  VSS96  = GND
  CA3_B  = M_A_CPU0_SB_CA<3>
  VSS97  = GND
  CA5_B  = M_A_CPU0_SB_CA<5>
  VSS98  = GND
  PAR_B  = M_A_CPU0_SB_PAR
  VSS99  = GND
  CS1_B_N  = M_A_CPU0_SB_CS_N<1>
  VSS100  = GND
  RFU5  = TP_CHA_CPU0_DIMM1_FRU_5
  RFU6  = TP_CHA_CPU0_DIMM1_FRU_6
  VSS101  = GND
  CB6_B  = M_A_CPU0_SB_CB<6>
  VSS102  = GND
  CB7_B  = M_A_CPU0_SB_CB<7>
  VSS103  = GND
  DQS4_B_C  = M_A_CPU0_SB_DQS_DN<4>
  DQS4_B_T  = M_A_CPU0_SB_DQS_DP<4>
  VSS104  = GND
  CB2_B  = M_A_CPU0_SB_CB<2>
  VSS105  = GND
  CB3_B  = M_A_CPU0_SB_CB<3>
  VSS106  = GND
  DQ2_B  = M_A_CPU0_SB_DQ<2>
  VSS107  = GND
  DQ3_B  = M_A_CPU0_SB_DQ<3>
  VSS108  = GND
  \dqs5_b_c||tdqs5_b_c\  = M_A_CPU0_SB_DQS_DN<5>
  \dqs5_b_t||tdqs5_b_t\  = M_A_CPU0_SB_DQS_DP<5>
  VSS109  = GND
  DQ6_B  = M_A_CPU0_SB_DQ<6>
  VSS110  = GND
  DQ7_B  = M_A_CPU0_SB_DQ<7>
  VSS111  = GND
  DQ10_B  = M_A_CPU0_SB_DQ<10>
  VSS112  = GND
  DQ11_B  = M_A_CPU0_SB_DQ<11>
  VSS113  = GND
  \dqs6_b_c||tdqs6_b_c\  = M_A_CPU0_SB_DQS_DN<6>
  \dqs6_b_t||tdqs6_b_t\  = M_A_CPU0_SB_DQS_DP<6>
  VSS114  = GND
  DQ14_B  = M_A_CPU0_SB_DQ<14>
  VSS115  = GND
  DQ15_B  = M_A_CPU0_SB_DQ<15>
  VSS116  = GND
  DQ18_B  = M_A_CPU0_SB_DQ<18>
  VSS117  = GND
  DQ19_B  = M_A_CPU0_SB_DQ<19>
  VSS118  = GND
  \dqs7_b_c||tdqs7_b_c\  = M_A_CPU0_SB_DQS_DN<7>
  \dqs7_b_t||tdqs7_b_t\  = M_A_CPU0_SB_DQS_DP<7>
  VSS119  = GND
  DQ22_B  = M_A_CPU0_SB_DQ<22>
  VSS120  = GND
  DQ23_B  = M_A_CPU0_SB_DQ<23>
  VSS121  = GND
  DQ26_B  = M_A_CPU0_SB_DQ<26>
  VSS122  = GND
  DQ27_B  = M_A_CPU0_SB_DQ<27>
  VSS123  = GND
  \dqs8_b_c||tdqs8_b_c\  = M_A_CPU0_SB_DQS_DN<8>
  \dqs8_b_t||tdqs8_b_t\  = M_A_CPU0_SB_DQS_DP<8>
  VSS124  = GND
  DQ30_B  = M_A_CPU0_SB_DQ<30>
  VSS125  = GND
  DQ31_B  = M_A_CPU0_SB_DQ<31>
  VSS126  = GND
  G1  = GND
  G2  = GND
  G3  = GND

(kicad_pcb
	(version 20260206)
	(generator "pcbnew")
	(generator_version "10.0")
	(general
		(thickness 1.6)
		(legacy_teardrops no)
	)
	(paper "A4")
	(title_block
		(title "03242023_DA0F0TMBIJ0_F0T_Motherboard_J_brd_V01_OCP.brd")
		(comment 1 "Grand Teton / footprint 1236 of 6105 (J1), pads 275-291 of 291")
	)
	(layers
		(0 "F.Cu" signal "TOP")
		(4 "In1.Cu" signal "GND")
		(6 "In2.Cu" signal "IN1")
		(8 "In3.Cu" signal "GND1")
		(10 "In4.Cu" signal "IN2")
		(12 "In5.Cu" signal "GND2")
		(14 "In6.Cu" signal "IN3")
		(16 "In7.Cu" signal "GND3")
		(18 "In8.Cu" signal "VCC")
		(20 "In9.Cu" signal "VCC1")
		(22 "In10.Cu" signal "GND4")
		(24 "In11.Cu" signal "IN4")
		(26 "In12.Cu" signal "GND5")
		(28 "In13.Cu" signal "IN5")
		(30 "In14.Cu" signal "GND6")
		(32 "In15.Cu" signal "IN6")
		(34 "In16.Cu" signal "GND7")
		(2 "B.Cu" signal "BOTTOM")
		(9 "F.Adhes" user "F.Adhesive")
		(11 "B.Adhes" user "B.Adhesive")
		(13 "F.Paste" user "Package Geometry/Pastemask Top")
		(15 "B.Paste" user "Package Geometry/Pastemask Bottom")
		(5 "F.SilkS" user "Ref Des/Silkscreen Top")
		(7 "B.SilkS" user "Ref Des/Silkscreen Bottom")
		(1 "F.Mask" user "Board Geometry/Soldermask Top")
		(3 "B.Mask" user "Board Geometry/Soldermask Bottom")
		(17 "Dwgs.User" user "User.Drawings")
		(19 "Cmts.User" user "User.Comments")
		(21 "Eco1.User" user "User.Eco1")
		(23 "Eco2.User" user "User.Eco2")
		(25 "Edge.Cuts" user "Board Geometry/Outline")
		(27 "Margin" user)
		(31 "F.CrtYd" user "Package Geometry/Place Bound Top")
		(29 "B.CrtYd" user "Package Geometry/Place Bound Bottom")
		(35 "F.Fab" user "Ref Des/Assembly Top")
		(33 "B.Fab" user "Ref Des/Assembly Bottom")
	)
	(footprint ""
		(layer "F.Cu")
		(at 303.393348 -258.091686)
		(property "Reference" "J1"
			(at -3.683 -81.702148 0)
			(unlocked yes)
			(layer "F.SilkS")
			(effects
				(font
					(size 0.7874 0.5842)
					(thickness 0.1524)
				)
				(justify left)
			)
		)
		(property "Value" ""
			(at 0 0 0)
			(layer "F.Fab")
			(effects
				(font
					(size 1.27 1.27)
				)
			)
		)
		(duplicate_pad_numbers_are_jumpers no)
		(pad "275" smd rect
			(at 2.050034 52.274978 270)
			(size 0.519938 1.4986)
			(layers "F.Cu" "F.Mask" "F.Paste")
			(net "GND")
		)
		(pad "276" smd rect
			(at 2.050034 53.125116 270)
			(size 0.519938 1.4986)
			(layers "F.Cu" "F.Mask" "F.Paste")
			(net "M_A_CPU0_SB_DQ<23>")
		)
		(pad "277" smd rect
			(at 2.050034 53.975 270)
			(size 0.519938 1.4986)
			(layers "F.Cu" "F.Mask" "F.Paste")
			(net "GND")
		)
		(pad "278" smd rect
			(at 2.050034 54.824884 270)
			(size 0.519938 1.4986)
			(layers "F.Cu" "F.Mask" "F.Paste")
			(net "M_A_CPU0_SB_DQ<26>")
		)
		(pad "279" smd rect
			(at 2.050034 55.675022 270)
			(size 0.519938 1.4986)
			(layers "F.Cu" "F.Mask" "F.Paste")
			(net "GND")
		)
		(pad "280" smd rect
			(at 2.050034 56.524906 270)
			(size 0.519938 1.4986)
			(layers "F.Cu" "F.Mask" "F.Paste")
			(net "M_A_CPU0_SB_DQ<27>")
		)
		(pad "281" smd rect
			(at 2.050034 57.375044 270)
			(size 0.519938 1.4986)
			(layers "F.Cu" "F.Mask" "F.Paste")
			(net "GND")
		)
		(pad "282" smd rect
			(at 2.050034 58.224928 270)
			(size 0.519938 1.4986)
			(layers "F.Cu" "F.Mask" "F.Paste")
			(net "M_A_CPU0_SB_DQS_DN<8>")
		)
		(pad "283" smd rect
			(at 2.050034 59.075066 270)
			(size 0.519938 1.4986)
			(layers "F.Cu" "F.Mask" "F.Paste")
			(net "M_A_CPU0_SB_DQS_DP<8>")
		)
		(pad "284" smd rect
			(at 2.050034 59.92495 270)
			(size 0.519938 1.4986)
			(layers "F.Cu" "F.Mask" "F.Paste")
			(net "GND")
		)
		(pad "285" smd rect
			(at 2.050034 60.775088 270)
			(size 0.519938 1.4986)
			(layers "F.Cu" "F.Mask" "F.Paste")
			(net "M_A_CPU0_SB_DQ<30>")
		)
		(pad "286" smd rect
			(at 2.050034 61.624972 270)
			(size 0.519938 1.4986)
			(layers "F.Cu" "F.Mask" "F.Paste")
			(net "GND")
		)
		(pad "287" smd rect
			(at 2.050034 62.47511 270)
			(size 0.519938 1.4986)
			(layers "F.Cu" "F.Mask" "F.Paste")
			(net "M_A_CPU0_SB_DQ<31>")
		)
		(pad "288" smd rect
			(at 2.050034 63.324994 270)
			(size 0.519938 1.4986)
			(layers "F.Cu" "F.Mask" "F.Paste")
			(net "GND")
		)
		(pad "G1" thru_hole oval
			(at 0 -68.97497)
			(size 2.8194 1.5748)
			(drill oval 2.4384 1.1938)
			(layers "*.Cu" "*.Mask")
			(remove_unused_layers no)
			(net "GND")
			(clearance 0.127)
			(thermal_gap 0.127)
		)
		(pad "G2" thru_hole oval
			(at 0 3.875024)
			(size 2.8194 1.5748)
			(drill oval 2.4384 1.1938)
			(layers "*.Cu" "*.Mask")
			(remove_unused_layers no)
			(net "GND")
			(clearance 0.127)
			(thermal_gap 0.127)
		)
		(pad "G3" thru_hole oval
			(at 0 68.97497)
			(size 2.8194 1.5748)
			(drill oval 2.4384 1.1938)
			(layers "*.Cu" "*.Mask")
			(remove_unused_layers no)
			(net "GND")
			(clearance 0.127)
			(thermal_gap 0.127)
		)
	)
)
